(kicad_pcb
	(version 20260206)
	(generator "pcbnew")
	(generator_version "10.0")
	(general
		(thickness 1.6)
		(legacy_teardrops no)
	)
	(paper "A4")
	(title_block
		(title "Bryce Canyon_IOM_IOC_16318-2_OCP.brd")
		(comment 1 "Bryce Canyon / footprints 164-170 of 1605")
	)
	(layers
		(0 "F.Cu" signal "TOP")
		(4 "In1.Cu" signal "L2GND")
		(6 "In2.Cu" signal "L3")
		(8 "In3.Cu" signal "L4VCC")
		(10 "In4.Cu" signal "L5VCC")
		(12 "In5.Cu" signal "L6")
		(14 "In6.Cu" signal "L7GND")
		(2 "B.Cu" signal "BOTTOM")
		(9 "F.Adhes" user "F.Adhesive")
		(11 "B.Adhes" user "B.Adhesive")
		(13 "F.Paste" user "Package Geometry/Pastemask Top")
		(15 "B.Paste" user "Package Geometry/Pastemask Bottom")
		(5 "F.SilkS" user "Ref Des/Silkscreen Top")
		(7 "B.SilkS" user "Ref Des/Silkscreen Bottom")
		(1 "F.Mask" user "Board Geometry/Soldermask Top")
		(3 "B.Mask" user "Board Geometry/Soldermask Bottom")
		(17 "Dwgs.User" user "User.Drawings")
		(19 "Cmts.User" user "User.Comments")
		(21 "Eco1.User" user "User.Eco1")
		(23 "Eco2.User" user "User.Eco2")
		(25 "Edge.Cuts" user "Board Geometry/Outline")
		(27 "Margin" user)
		(31 "F.CrtYd" user "Package Geometry/Place Bound Top")
		(29 "B.CrtYd" user "Package Geometry/Place Bound Bottom")
		(35 "F.Fab" user "Ref Des/Assembly Top")
		(33 "B.Fab" user "Ref Des/Assembly Bottom")
	)
	(footprint ""
		(layer "F.Cu")
		(at 28.194 -152.654 -90)
		(property "Reference" "R769"
			(at 0 0 270)
			(layer "F.SilkS")
			(hide yes)
			(effects
				(font
					(size 1.27 1.27)
				)
			)
		)
		(property "Value" "0R2J-2-GP"
			(at 0.064008 -3.993896 270)
			(unlocked yes)
			(layer "F.Fab")
			(hide yes)
			(effects
				(font
					(size 1.016 1.016)
					(thickness 0.1524)
				)
			)
		)
		(property "Device Type" "R402H16"
			(at 0.064008 -5.517896 270)
			(unlocked yes)
			(layer "F.Fab")
			(hide yes)
			(effects
				(font
					(size 1.016 1.016)
					(thickness 0.1524)
				)
			)
		)
		(duplicate_pad_numbers_are_jumpers no)
		(fp_line
			(start -0.508 -0.9398)
			(end -0.508 0.9398)
			(stroke
				(width 0.1524)
				(type default)
			)
			(layer "F.SilkS")
		)
		(fp_line
			(start 0.508 -0.9398)
			(end -0.508 -0.9398)
			(stroke
				(width 0.1524)
				(type default)
			)
			(layer "F.SilkS")
		)
		(fp_rect
			(start -0.508 0.9398)
			(end 0.508 -0.9398)
			(stroke
				(width 0)
				(type default)
			)
			(fill no)
			(layer "F.CrtYd")
		)
		(fp_rect
			(start -0.508 0.9398)
			(end 0.508 -0.9398)
			(stroke
				(width 0)
				(type default)
			)
			(fill no)
			(layer "F.Fab")
		)
		(pad "1" smd custom
			(at 0 -0.4445 270)
			(size 0.1397 0.1397)
			(layers "F.Cu" "F.Mask" "F.Paste")
			(net "DEBUG_GPIO_BMC_R_2")
			(options
				(clearance outline)
				(anchor circle)
			)
			(primitives
				(gr_poly
					(pts
						(arc
							(start -0.1778 -0.2794)
							(mid -0.249642 -0.249642)
							(end -0.2794 -0.1778)
						)
						(arc
							(start -0.2794 0.1778)
							(mid -0.249642 0.249642)
							(end -0.1778 0.2794)
						)
						(arc
							(start 0.1778 0.2794)
							(mid 0.249642 0.249642)
							(end 0.2794 0.1778)
						)
						(arc
							(start 0.2794 -0.1778)
							(mid 0.249642 -0.249642)
							(end 0.1778 -0.2794)
						)
					)
					(width 0)
					(fill yes)
				)
			)
		)
		(pad "2" smd custom
			(at 0 0.4445 270)
			(size 0.1397 0.1397)
			(layers "F.Cu" "F.Mask" "F.Paste")
			(net "DEBUG_GPIO_BMC_2")
			(options
				(clearance outline)
				(anchor circle)
			)
			(primitives
				(gr_poly
					(pts
						(arc
							(start -0.1778 -0.2794)
							(mid -0.249642 -0.249642)
							(end -0.2794 -0.1778)
						)
						(arc
							(start -0.2794 0.1778)
							(mid -0.249642 0.249642)
							(end -0.1778 0.2794)
						)
						(arc
							(start 0.1778 0.2794)
							(mid 0.249642 0.249642)
							(end 0.2794 0.1778)
						)
						(arc
							(start 0.2794 -0.1778)
							(mid 0.249642 -0.249642)
							(end 0.1778 -0.2794)
						)
					)
					(width 0)
					(fill yes)
				)
			)
		)
	)
	(footprint ""
		(layer "F.Cu")
		(at 28.321 -157.734 -90)
		(property "Reference" "R773"
			(at 0 0 270)
			(layer "F.SilkS")
			(hide yes)
			(effects
				(font
					(size 1.27 1.27)
				)
			)
		)
		(property "Value" "0R2J-2-GP"
			(at 0.064008 -3.993896 270)
			(unlocked yes)
			(layer "F.Fab")
			(hide yes)
			(effects
				(font
					(size 1.016 1.016)
					(thickness 0.1524)
				)
			)
		)
		(property "Device Type" "R402H16"
			(at 0.064008 -5.517896 270)
			(unlocked yes)
			(layer "F.Fab")
			(hide yes)
			(effects
				(font
					(size 1.016 1.016)
					(thickness 0.1524)
				)
			)
		)
		(duplicate_pad_numbers_are_jumpers no)
		(fp_line
			(start -0.508 -0.9398)
			(end -0.508 0.9398)
			(stroke
				(width 0.1524)
				(type default)
			)
			(layer "F.SilkS")
		)
		(fp_line
			(start 0.508 -0.9398)
			(end -0.508 -0.9398)
			(stroke
				(width 0.1524)
				(type default)
			)
			(layer "F.SilkS")
		)
		(fp_rect
			(start -0.508 0.9398)
			(end 0.508 -0.9398)
			(stroke
				(width 0)
				(type default)
			)
			(fill no)
			(layer "F.CrtYd")
		)
		(fp_rect
			(start -0.508 0.9398)
			(end 0.508 -0.9398)
			(stroke
				(width 0)
				(type default)
			)
			(fill no)
			(layer "F.Fab")
		)
		(pad "1" smd custom
			(at 0 -0.4445 270)
			(size 0.1397 0.1397)
			(layers "F.Cu" "F.Mask" "F.Paste")
			(net "DEBUG_GPIO_BMC_R_6")
			(options
				(clearance outline)
				(anchor circle)
			)
			(primitives
				(gr_poly
					(pts
						(arc
							(start -0.1778 -0.2794)
							(mid -0.249642 -0.249642)
							(end -0.2794 -0.1778)
						)
						(arc
							(start -0.2794 0.1778)
							(mid -0.249642 0.249642)
							(end -0.1778 0.2794)
						)
						(arc
							(start 0.1778 0.2794)
							(mid 0.249642 0.249642)
							(end 0.2794 0.1778)
						)
						(arc
							(start 0.2794 -0.1778)
							(mid 0.249642 -0.249642)
							(end 0.1778 -0.2794)
						)
					)
					(width 0)
					(fill yes)
				)
			)
		)
		(pad "2" smd custom
			(at 0 0.4445 270)
			(size 0.1397 0.1397)
			(layers "F.Cu" "F.Mask" "F.Paste")
			(net "DEBUG_GPIO_BMC_6")
			(options
				(clearance outline)
				(anchor circle)
			)
			(primitives
				(gr_poly
					(pts
						(arc
							(start -0.1778 -0.2794)
							(mid -0.249642 -0.249642)
							(end -0.2794 -0.1778)
						)
						(arc
							(start -0.2794 0.1778)
							(mid -0.249642 0.249642)
							(end -0.1778 0.2794)
						)
						(arc
							(start 0.1778 0.2794)
							(mid 0.249642 0.249642)
							(end 0.2794 0.1778)
						)
						(arc
							(start 0.2794 -0.1778)
							(mid 0.249642 -0.249642)
							(end 0.1778 -0.2794)
						)
					)
					(width 0)
					(fill yes)
				)
			)
		)
	)
	(footprint ""
		(layer "F.Cu")
		(at 78.122018 -77.353668 90)
		(property "Reference" "VIA3"
			(at 0 0 90)
			(layer "F.SilkS")
			(hide yes)
			(effects
				(font
					(size 1.27 1.27)
				)
			)
		)
		(property "Value" "85OHM-8L-1D6MM-L16L18-GP"
			(at 4.064 0.6096 90)
			(unlocked yes)
			(layer "F.Fab")
			(hide yes)
			(effects
				(font
					(size 1.016 1.016)
					(thickness 0.1524)
				)
			)
		)
		(property "Device Type" "VIA-PCIE-4P-368076"
			(at 4.064 -0.9144 90)
			(unlocked yes)
			(layer "F.Fab")
			(hide yes)
			(effects
				(font
					(size 1.016 1.016)
					(thickness 0.1524)
				)
			)
		)
		(duplicate_pad_numbers_are_jumpers no)
		(fp_rect
			(start -1.8415 0.381)
			(end 1.8415 -0.381)
			(stroke
				(width 0)
				(type default)
			)
			(fill no)
			(layer "F.CrtYd")
		)
		(fp_rect
			(start -1.8415 0.381)
			(end 1.8415 -0.381)
			(stroke
				(width 0)
				(type default)
			)
			(fill no)
			(layer "F.Fab")
		)
		(pad "1" thru_hole circle
			(at -1.4605 0 90)
			(size 0.508 0.508)
			(drill 0.254)
			(layers "*.Cu" "*.Mask")
			(remove_unused_layers no)
			(net "GND")
			(clearance 0.127)
			(thermal_gap 0.127)
		)
		(pad "2" thru_hole circle
			(at -0.4445 0 90)
			(size 0.508 0.508)
			(drill 0.254)
			(layers "*.Cu" "*.Mask")
			(remove_unused_layers no)
			(net "PCIE_COMP_TO_IOM_18_DP")
			(clearance 0.127)
			(thermal_gap 0.127)
		)
		(pad "3" thru_hole circle
			(at 0.4445 0 90)
			(size 0.508 0.508)
			(drill 0.254)
			(layers "*.Cu" "*.Mask")
			(remove_unused_layers no)
			(net "PCIE_COMP_TO_IOM_18_DN")
			(clearance 0.127)
			(thermal_gap 0.127)
		)
		(pad "4" thru_hole circle
			(at 1.4605 0 90)
			(size 0.508 0.508)
			(drill 0.254)
			(layers "*.Cu" "*.Mask")
			(remove_unused_layers no)
			(net "GND")
			(clearance 0.127)
			(thermal_gap 0.127)
		)
	)
	(footprint ""
		(layer "F.Cu")
		(at 88.222074 -61.534294 -90)
		(property "Reference" "R5"
			(at 0 0 270)
			(layer "F.SilkS")
			(hide yes)
			(effects
				(font
					(size 1.27 1.27)
				)
			)
		)
		(property "Value" "0R2J-2-GP"
			(at 0.064008 -3.993896 270)
			(unlocked yes)
			(layer "F.Fab")
			(hide yes)
			(effects
				(font
					(size 1.016 1.016)
					(thickness 0.1524)
				)
			)
		)
		(property "Device Type" "R402H16"
			(at 0.064008 -5.517896 270)
			(unlocked yes)
			(layer "F.Fab")
			(hide yes)
			(effects
				(font
					(size 1.016 1.016)
					(thickness 0.1524)
				)
			)
		)
		(duplicate_pad_numbers_are_jumpers no)
		(fp_line
			(start -0.508 -0.9398)
			(end -0.508 0.9398)
			(stroke
				(width 0.1524)
				(type default)
			)
			(layer "F.SilkS")
		)
		(fp_line
			(start 0.508 -0.9398)
			(end -0.508 -0.9398)
			(stroke
				(width 0.1524)
				(type default)
			)
			(layer "F.SilkS")
		)
		(fp_rect
			(start -0.508 0.9398)
			(end 0.508 -0.9398)
			(stroke
				(width 0)
				(type default)
			)
			(fill no)
			(layer "F.CrtYd")
		)
		(fp_rect
			(start -0.508 0.9398)
			(end 0.508 -0.9398)
			(stroke
				(width 0)
				(type default)
			)
			(fill no)
			(layer "F.Fab")
		)
		(pad "1" smd custom
			(at 0 -0.4445 270)
			(size 0.1397 0.1397)
			(layers "F.Cu" "F.Mask" "F.Paste")
			(net "NCSI_RCSDV")
			(options
				(clearance outline)
				(anchor circle)
			)
			(primitives
				(gr_poly
					(pts
						(arc
							(start -0.1778 -0.2794)
							(mid -0.249642 -0.249642)
							(end -0.2794 -0.1778)
						)
						(arc
							(start -0.2794 0.1778)
							(mid -0.249642 0.249642)
							(end -0.1778 0.2794)
						)
						(arc
							(start 0.1778 0.2794)
							(mid 0.249642 0.249642)
							(end 0.2794 0.1778)
						)
						(arc
							(start 0.2794 -0.1778)
							(mid 0.249642 -0.249642)
							(end 0.1778 -0.2794)
						)
					)
					(width 0)
					(fill yes)
				)
			)
		)
		(pad "2" smd custom
			(at 0 0.4445 270)
			(size 0.1397 0.1397)
			(layers "F.Cu" "F.Mask" "F.Paste")
			(net "NCSI_RCSDV_R")
			(options
				(clearance outline)
				(anchor circle)
			)
			(primitives
				(gr_poly
					(pts
						(arc
							(start -0.1778 -0.2794)
							(mid -0.249642 -0.249642)
							(end -0.2794 -0.1778)
						)
						(arc
							(start -0.2794 0.1778)
							(mid -0.249642 0.249642)
							(end -0.1778 0.2794)
						)
						(arc
							(start 0.1778 0.2794)
							(mid 0.249642 0.249642)
							(end 0.2794 0.1778)
						)
						(arc
							(start 0.2794 -0.1778)
							(mid 0.249642 -0.249642)
							(end 0.1778 -0.2794)
						)
					)
					(width 0)
					(fill yes)
				)
			)
		)
	)
	(footprint ""
		(layer "F.Cu")
		(at 92.386404 -46.654974 90)
		(property "Reference" "PQ2"
			(at 0 0 90)
			(layer "F.SilkS")
			(hide yes)
			(effects
				(font
					(size 1.27 1.27)
				)
			)
		)
		(property "Value" "2N7002K-1-GP"
			(at 0.127 -8.9662 90)
			(unlocked yes)
			(layer "F.Fab")
			(hide yes)
			(effects
				(font
					(size 1.016 1.016)
					(thickness 0.1524)
				)
			)
		)
		(property "Device Type" "SOT23DGS2D4H44"
			(at 0.127 -10.4902 90)
			(unlocked yes)
			(layer "F.Fab")
			(hide yes)
			(effects
				(font
					(size 1.016 1.016)
					(thickness 0.1524)
				)
			)
		)
		(duplicate_pad_numbers_are_jumpers no)
		(fp_line
			(start 1.651 -1.778)
			(end -1.651 -1.778)
			(stroke
				(width 0.1524)
				(type default)
			)
			(layer "F.SilkS")
		)
		(fp_line
			(start -1.651 -1.778)
			(end -1.651 1.778)
			(stroke
				(width 0.1524)
				(type default)
			)
			(layer "F.SilkS")
		)
		(fp_line
			(start 1.651 1.778)
			(end 1.651 -1.778)
			(stroke
				(width 0.1524)
				(type default)
			)
			(layer "F.SilkS")
		)
		(fp_line
			(start -1.651 1.778)
			(end 1.651 1.778)
			(stroke
				(width 0.1524)
				(type default)
			)
			(layer "F.SilkS")
		)
		(fp_poly
			(pts
				(xy -1.778 1.8796) (xy -1.778 -1.8796) (xy 1.778 -1.8796) (xy 1.778 1.8796)
			)
			(stroke
				(width 0)
				(type default)
			)
			(fill no)
			(layer "F.CrtYd")
		)
		(fp_poly
			(pts
				(xy -1.778 1.8796) (xy -1.778 -1.8796) (xy 1.778 -1.8796) (xy 1.778 1.8796)
			)
			(stroke
				(width 0)
				(type default)
			)
			(fill no)
			(layer "F.Fab")
		)
		(pad "D" smd custom
			(at 0 -0.9525 90)
			(size 0.1905 0.1905)
			(layers "F.Cu" "F.Mask" "F.Paste")
			(net "PQ2_D")
			(options
				(clearance outline)
				(anchor circle)
			)
			(primitives
				(gr_poly
					(pts
						(arc
							(start -0.1778 0.5715)
							(mid -0.321484 0.511984)
							(end -0.381 0.3683)
						)
						(arc
							(start -0.381 -0.3683)
							(mid -0.321484 -0.511984)
							(end -0.1778 -0.5715)
						)
						(arc
							(start 0.1778 -0.5715)
							(mid 0.321484 -0.511984)
							(end 0.381 -0.3683)
						)
						(arc
							(start 0.381 0.3683)
							(mid 0.321484 0.511984)
							(end 0.1778 0.5715)
						)
					)
					(width 0)
					(fill yes)
				)
			)
		)
		(pad "G" smd custom
			(at -0.98425 0.9525 90)
			(size 0.1905 0.1905)
			(layers "F.Cu" "F.Mask" "F.Paste")
			(net "PQ2_G")
			(options
				(clearance outline)
				(anchor circle)
			)
			(primitives
				(gr_poly
					(pts
						(arc
							(start -0.1778 0.5715)
							(mid -0.321484 0.511984)
							(end -0.381 0.3683)
						)
						(arc
							(start -0.381 -0.3683)
							(mid -0.321484 -0.511984)
							(end -0.1778 -0.5715)
						)
						(arc
							(start 0.1778 -0.5715)
							(mid 0.321484 -0.511984)
							(end 0.381 -0.3683)
						)
						(arc
							(start 0.381 0.3683)
							(mid 0.321484 0.511984)
							(end 0.1778 0.5715)
						)
					)
					(width 0)
					(fill yes)
				)
			)
		)
		(pad "S" smd custom
			(at 0.98425 0.9525 90)
			(size 0.1905 0.1905)
			(layers "F.Cu" "F.Mask" "F.Paste")
			(net "P3V3_EN_R")
			(options
				(clearance outline)
				(anchor circle)
			)
			(primitives
				(gr_poly
					(pts
						(arc
							(start -0.1778 0.5715)
							(mid -0.321484 0.511984)
							(end -0.381 0.3683)
						)
						(arc
							(start -0.381 -0.3683)
							(mid -0.321484 -0.511984)
							(end -0.1778 -0.5715)
						)
						(arc
							(start 0.1778 -0.5715)
							(mid 0.321484 -0.511984)
							(end 0.381 -0.3683)
						)
						(arc
							(start 0.381 0.3683)
							(mid 0.321484 0.511984)
							(end 0.1778 0.5715)
						)
					)
					(width 0)
					(fill yes)
				)
			)
		)
	)
	(footprint ""
		(layer "F.Cu")
		(at 66.394584 -160.038034 -90)
		(property "Reference" "R774"
			(at 0 0 270)
			(layer "F.SilkS")
			(hide yes)
			(effects
				(font
					(size 1.27 1.27)
				)
			)
		)
		(property "Value" "1KR2F-3-GP"
			(at 0.064008 -3.993896 270)
			(unlocked yes)
			(layer "F.Fab")
			(hide yes)
			(effects
				(font
					(size 1.016 1.016)
					(thickness 0.1524)
				)
			)
		)
		(property "Device Type" "R402H16"
			(at 0.064008 -5.517896 270)
			(unlocked yes)
			(layer "F.Fab")
			(hide yes)
			(effects
				(font
					(size 1.016 1.016)
					(thickness 0.1524)
				)
			)
		)
		(duplicate_pad_numbers_are_jumpers no)
		(fp_line
			(start -0.508 -0.9398)
			(end -0.508 0.9398)
			(stroke
				(width 0.1524)
				(type default)
			)
			(layer "F.SilkS")
		)
		(fp_line
			(start 0.508 -0.9398)
			(end -0.508 -0.9398)
			(stroke
				(width 0.1524)
				(type default)
			)
			(layer "F.SilkS")
		)
		(fp_rect
			(start -0.508 0.9398)
			(end 0.508 -0.9398)
			(stroke
				(width 0)
				(type default)
			)
			(fill no)
			(layer "F.CrtYd")
		)
		(fp_rect
			(start -0.508 0.9398)
			(end 0.508 -0.9398)
			(stroke
				(width 0)
				(type default)
			)
			(fill no)
			(layer "F.Fab")
		)
		(pad "1" smd custom
			(at 0 -0.4445 270)
			(size 0.1397 0.1397)
			(layers "F.Cu" "F.Mask" "F.Paste")
			(net "P1V15_STBY")
			(options
				(clearance outline)
				(anchor circle)
			)
			(primitives
				(gr_poly
					(pts
						(arc
							(start -0.1778 -0.2794)
							(mid -0.249642 -0.249642)
							(end -0.2794 -0.1778)
						)
						(arc
							(start -0.2794 0.1778)
							(mid -0.249642 0.249642)
							(end -0.1778 0.2794)
						)
						(arc
							(start 0.1778 0.2794)
							(mid 0.249642 0.249642)
							(end 0.2794 0.1778)
						)
						(arc
							(start 0.2794 -0.1778)
							(mid 0.249642 -0.249642)
							(end 0.1778 -0.2794)
						)
					)
					(width 0)
					(fill yes)
				)
			)
		)
		(pad "2" smd custom
			(at 0 0.4445 270)
			(size 0.1397 0.1397)
			(layers "F.Cu" "F.Mask" "F.Paste")
			(net "ADC_P1V15_STBY")
			(options
				(clearance outline)
				(anchor circle)
			)
			(primitives
				(gr_poly
					(pts
						(arc
							(start -0.1778 -0.2794)
							(mid -0.249642 -0.249642)
							(end -0.2794 -0.1778)
						)
						(arc
							(start -0.2794 0.1778)
							(mid -0.249642 0.249642)
							(end -0.1778 0.2794)
						)
						(arc
							(start 0.1778 0.2794)
							(mid 0.249642 0.249642)
							(end 0.2794 0.1778)
						)
						(arc
							(start 0.2794 -0.1778)
							(mid 0.249642 -0.249642)
							(end 0.1778 -0.2794)
						)
					)
					(width 0)
					(fill yes)
				)
			)
		)
	)
	(footprint ""
		(layer "F.Cu")
		(at 66.276474 -175.088296)
		(property "Reference" "U10"
			(at 0 0 0)
			(layer "F.SilkS")
			(hide yes)
			(effects
				(font
					(size 1.27 1.27)
				)
			)
		)
		(property "Value" "LMV331IDCKRG4-GP"
			(at -2.3368 -8.6868 0)
			(unlocked yes)
			(layer "F.Fab")
			(hide yes)
			(effects
				(font
					(size 1.016 1.016)
					(thickness 0.1524)
				)
			)
		)
		(property "Device Type" "SC70-5H44"
			(at -2.3114 -10.414 0)
			(unlocked yes)
			(layer "F.Fab")
			(hide yes)
			(effects
				(font
					(size 1.016 1.016)
					(thickness 0.1524)
				)
			)
		)
		(duplicate_pad_numbers_are_jumpers no)
		(fp_line
			(start -1.27 -1.7018)
			(end 1.27 -1.7018)
			(stroke
				(width 0.1524)
				(type default)
			)
			(layer "F.SilkS")
		)
		(fp_line
			(start -1.27 1.7018)
			(end -1.27 -1.7018)
			(stroke
				(width 0.1524)
				(type default)
			)
			(layer "F.SilkS")
		)
		(fp_line
			(start 0.6604 -1.8034)
			(end 1.3843 -1.8034)
			(stroke
				(width 0.3302)
				(type default)
			)
			(layer "F.SilkS")
		)
		(fp_line
			(start 1.27 -1.7018)
			(end 1.27 1.7018)
			(stroke
				(width 0.1524)
				(type default)
			)
			(layer "F.SilkS")
		)
		(fp_line
			(start 1.27 1.7018)
			(end -1.27 1.7018)
			(stroke
				(width 0.1524)
				(type default)
			)
			(layer "F.SilkS")
		)
		(fp_line
			(start 1.3843 -1.8034)
			(end 1.3843 -1.1176)
			(stroke
				(width 0.3302)
				(type default)
			)
			(layer "F.SilkS")
		)
		(fp_rect
			(start -1.524 1.9558)
			(end 1.524 -1.9558)
			(stroke
				(width 0)
				(type default)
			)
			(fill no)
			(layer "F.CrtYd")
		)
		(fp_poly
			(pts
				(xy -1.524 -1.9558) (xy 1.524 -1.9558) (xy 1.524 1.9558) (xy -1.524 1.9558)
			)
			(stroke
				(width 0)
				(type default)
			)
			(fill no)
			(layer "F.Fab")
		)
		(pad "1" smd rect
			(at 0.65024 -0.8255)
			(size 0.4064 1.2192)
			(layers "F.Cu" "F.Mask" "F.Paste")
			(net "FM_TPM_PRSNT_RST_N")
		)
		(pad "2" smd rect
			(at 0 -0.8255)
			(size 0.4064 1.2192)
			(layers "F.Cu" "F.Mask" "F.Paste")
			(net "GND")
		)
		(pad "3" smd rect
			(at -0.65024 -0.8255)
			(size 0.4064 1.2192)
			(layers "F.Cu" "F.Mask" "F.Paste")
			(net "VREF_2V2")
		)
		(pad "4" smd rect
			(at -0.65024 0.8255)
			(size 0.4064 1.2192)
			(layers "F.Cu" "F.Mask" "F.Paste")
			(net "FM_TPM_PRSNT_N")
		)
		(pad "5" smd rect
			(at 0.65024 0.8255)
			(size 0.4064 1.2192)
			(layers "F.Cu" "F.Mask" "F.Paste")
			(net "P5V_STBY")
		)
	)
)
